(kicad_pcb
	(version 20260206)
	(generator "pcbnew")
	(generator_version "10.0")
	(general
		(thickness 1.6)
		(legacy_teardrops no)
	)
	(paper "A4")
	(title_block
		(title "Wiwynn_Tioga_Pass_MB.brd")
		(comment 1 "Tioga Pass / footprints 2776-2783 of 4770")
	)
	(layers
		(0 "F.Cu" signal "TOP")
		(4 "In1.Cu" signal "L2GND")
		(6 "In2.Cu" signal "L3")
		(8 "In3.Cu" signal "L4GND")
		(10 "In4.Cu" signal "L5")
		(12 "In5.Cu" signal "L6GND")
		(14 "In6.Cu" signal "L7VCC")
		(16 "In7.Cu" signal "L8VCC")
		(18 "In8.Cu" signal "L9GND")
		(20 "In9.Cu" signal "L10")
		(22 "In10.Cu" signal "L11GND")
		(24 "In11.Cu" signal "L12")
		(26 "In12.Cu" signal "L13GND")
		(2 "B.Cu" signal "BOTTOM")
		(9 "F.Adhes" user "F.Adhesive")
		(11 "B.Adhes" user "B.Adhesive")
		(13 "F.Paste" user "Package Geometry/Pastemask Top")
		(15 "B.Paste" user "Package Geometry/Pastemask Bottom")
		(5 "F.SilkS" user "Ref Des/Silkscreen Top")
		(7 "B.SilkS" user "Ref Des/Silkscreen Bottom")
		(1 "F.Mask" user "Board Geometry/Soldermask Top")
		(3 "B.Mask" user "Board Geometry/Soldermask Bottom")
		(17 "Dwgs.User" user "User.Drawings")
		(19 "Cmts.User" user "User.Comments")
		(21 "Eco1.User" user "User.Eco1")
		(23 "Eco2.User" user "User.Eco2")
		(25 "Edge.Cuts" user "Board Geometry/Outline")
		(27 "Margin" user)
		(31 "F.CrtYd" user "Package Geometry/Place Bound Top")
		(29 "B.CrtYd" user "Package Geometry/Place Bound Bottom")
		(35 "F.Fab" user "Ref Des/Assembly Top")
		(33 "B.Fab" user "Ref Des/Assembly Bottom")
	)
	(footprint ""
		(layer "B.Cu")
		(at 214.503 -59.17692 180)
		(property "Reference" "C6R7"
			(at 0 0 0)
			(layer "B.SilkS")
			(hide yes)
			(effects
				(font
					(size 1.27 1.27)
				)
				(justify mirror)
			)
		)
		(property "Value" ""
			(at 0 0 0)
			(layer "B.Fab")
			(effects
				(font
					(size 1.27 1.27)
				)
				(justify mirror)
			)
		)
		(duplicate_pad_numbers_are_jumpers no)
		(fp_poly
			(pts
				(xy 0.4953 -0.2032) (xy -0.4953 -0.2032) (xy -0.4953 1.6002) (xy 0.4953 1.6002)
			)
			(stroke
				(width 0)
				(type default)
			)
			(fill no)
			(layer "B.CrtYd")
		)
		(fp_line
			(start 0.4953 1.6002)
			(end 0.4953 -0.2032)
			(stroke
				(width 0.1)
				(type default)
			)
			(layer "B.Fab")
		)
		(fp_line
			(start 0.4953 -0.2032)
			(end -0.4953 -0.2032)
			(stroke
				(width 0.1)
				(type default)
			)
			(layer "B.Fab")
		)
		(fp_line
			(start -0.4953 1.6002)
			(end 0.4953 1.6002)
			(stroke
				(width 0.1)
				(type default)
			)
			(layer "B.Fab")
		)
		(fp_line
			(start -0.4953 -0.2032)
			(end -0.4953 1.6002)
			(stroke
				(width 0.1)
				(type default)
			)
			(layer "B.Fab")
		)
		(pad "1" smd rect
			(at 0 0)
			(size 0.762 0.889)
			(layers "B.Cu" "B.Mask" "B.Paste")
			(net "PVCCIN_CPU0")
		)
		(pad "2" smd rect
			(at 0 1.397)
			(size 0.762 0.889)
			(layers "B.Cu" "B.Mask" "B.Paste")
			(net "GND")
		)
		(zone
			(layer "B.Cu")
			(hatch none 0.5)
			(connect_pads
				(clearance 0)
			)
			(min_thickness 0.25)
			(keepout
				(tracks not_allowed)
				(vias allowed)
				(pads allowed)
				(copperpour not_allowed)
				(footprints allowed)
			)
			(placement
				(enabled no)
				(sheetname "")
			)
			(fill
				(thermal_gap 0.5)
				(thermal_bridge_width 0.5)
				(island_removal_mode 0)
			)
			(polygon
				(pts
					(xy 214.122 -59.62142) (xy 214.884 -59.62142) (xy 214.884 -60.12942) (xy 214.122 -60.12942)
				)
			)
		)
	)
	(footprint ""
		(layer "B.Cu")
		(at 446.53835 -29.6164)
		(property "Reference" "C25W11"
			(at 0.8382 -0.67818 0)
			(unlocked yes)
			(layer "B.SilkS")
			(effects
				(font
					(size 0.4064 0.254)
					(thickness 0.1524)
				)
				(justify left mirror)
			)
		)
		(property "Value" ""
			(at 0 0 0)
			(layer "B.Fab")
			(effects
				(font
					(size 1.27 1.27)
				)
				(justify mirror)
			)
		)
		(duplicate_pad_numbers_are_jumpers no)
		(fp_poly
			(pts
				(xy -0.3048 -0.1016) (xy -0.3048 0.9906) (xy 0.3048 0.9906) (xy 0.3048 -0.1016)
			)
			(stroke
				(width 0)
				(type default)
			)
			(fill no)
			(layer "B.CrtYd")
		)
		(fp_line
			(start -0.3048 -0.1016)
			(end 0.3048 -0.1016)
			(stroke
				(width 0.1)
				(type default)
			)
			(layer "B.Fab")
		)
		(fp_line
			(start -0.3048 0.9906)
			(end -0.3048 -0.1016)
			(stroke
				(width 0.1)
				(type default)
			)
			(layer "B.Fab")
		)
		(fp_line
			(start 0.3048 -0.1016)
			(end 0.3048 0.9906)
			(stroke
				(width 0.1)
				(type default)
			)
			(layer "B.Fab")
		)
		(fp_line
			(start 0.3048 0.9906)
			(end -0.3048 0.9906)
			(stroke
				(width 0.1)
				(type default)
			)
			(layer "B.Fab")
		)
		(pad "1" smd rect
			(at 0 0 180)
			(size 0.508 0.508)
			(layers "B.Cu" "B.Mask" "B.Paste")
			(net "BMC_M_VREFCA")
		)
		(pad "2" smd rect
			(at 0 0.889 180)
			(size 0.508 0.508)
			(layers "B.Cu" "B.Mask" "B.Paste")
			(net "GND")
		)
		(zone
			(layer "B.Cu")
			(hatch none 0.5)
			(connect_pads
				(clearance 0)
			)
			(min_thickness 0.25)
			(keepout
				(tracks allowed)
				(vias not_allowed)
				(pads allowed)
				(copperpour not_allowed)
				(footprints allowed)
			)
			(placement
				(enabled no)
				(sheetname "")
			)
			(fill
				(thermal_gap 0.5)
				(thermal_bridge_width 0.5)
				(island_removal_mode 0)
			)
			(polygon
				(pts
					(xy 446.79235 -29.3624) (xy 446.28435 -29.3624) (xy 446.28435 -28.9814) (xy 446.79235 -28.9814)
				)
			)
		)
		(zone
			(layer "B.Cu")
			(hatch none 0.5)
			(connect_pads
				(clearance 0)
			)
			(min_thickness 0.25)
			(keepout
				(tracks not_allowed)
				(vias allowed)
				(pads allowed)
				(copperpour not_allowed)
				(footprints allowed)
			)
			(placement
				(enabled no)
				(sheetname "")
			)
			(fill
				(thermal_gap 0.5)
				(thermal_bridge_width 0.5)
				(island_removal_mode 0)
			)
			(polygon
				(pts
					(xy 446.79235 -28.9814) (xy 446.28435 -28.9814) (xy 446.28435 -29.3624) (xy 446.79235 -29.3624)
				)
			)
		)
	)
	(footprint ""
		(layer "B.Cu")
		(at 405.3586 -34.313368 90)
		(property "Reference" "R25W121"
			(at 0.8382 -0.67818 90)
			(unlocked yes)
			(layer "B.SilkS")
			(effects
				(font
					(size 0.4064 0.254)
					(thickness 0.1524)
				)
				(justify left mirror)
			)
		)
		(property "Value" ""
			(at 0 0 90)
			(layer "B.Fab")
			(effects
				(font
					(size 1.27 1.27)
				)
				(justify mirror)
			)
		)
		(duplicate_pad_numbers_are_jumpers no)
		(fp_poly
			(pts
				(xy 0.2794 -0.1016) (xy -0.2794 -0.1016) (xy -0.2794 0.9906) (xy 0.2794 0.9906)
			)
			(stroke
				(width 0)
				(type default)
			)
			(fill no)
			(layer "B.CrtYd")
		)
		(fp_line
			(start 0.2794 -0.1016)
			(end 0.2794 0.9906)
			(stroke
				(width 0.1)
				(type default)
			)
			(layer "B.Fab")
		)
		(fp_line
			(start -0.2794 -0.1016)
			(end 0.2794 -0.1016)
			(stroke
				(width 0.1)
				(type default)
			)
			(layer "B.Fab")
		)
		(fp_line
			(start 0.2794 0.9906)
			(end -0.2794 0.9906)
			(stroke
				(width 0.1)
				(type default)
			)
			(layer "B.Fab")
		)
		(fp_line
			(start -0.2794 0.9906)
			(end -0.2794 -0.1016)
			(stroke
				(width 0.1)
				(type default)
			)
			(layer "B.Fab")
		)
		(pad "1" smd rect
			(at 0 0 270)
			(size 0.508 0.508)
			(layers "B.Cu" "B.Mask" "B.Paste")
			(net "SMB_PEHPCPU0_STBY_LVC3_R_SDA")
		)
		(pad "2" smd rect
			(at 0 0.889 270)
			(size 0.508 0.508)
			(layers "B.Cu" "B.Mask" "B.Paste")
			(net "SMB_PEHPCPU0_STBY_LVC3_R2_SDA")
		)
		(zone
			(layer "B.Cu")
			(hatch none 0.5)
			(connect_pads
				(clearance 0)
			)
			(min_thickness 0.25)
			(keepout
				(tracks allowed)
				(vias not_allowed)
				(pads allowed)
				(copperpour not_allowed)
				(footprints allowed)
			)
			(placement
				(enabled no)
				(sheetname "")
			)
			(fill
				(thermal_gap 0.5)
				(thermal_bridge_width 0.5)
				(island_removal_mode 0)
			)
			(polygon
				(pts
					(xy 405.6126 -34.567368) (xy 405.6126 -34.059368) (xy 405.9936 -34.059368) (xy 405.9936 -34.567368)
				)
			)
		)
		(zone
			(layer "B.Cu")
			(hatch none 0.5)
			(connect_pads
				(clearance 0)
			)
			(min_thickness 0.25)
			(keepout
				(tracks not_allowed)
				(vias allowed)
				(pads allowed)
				(copperpour not_allowed)
				(footprints allowed)
			)
			(placement
				(enabled no)
				(sheetname "")
			)
			(fill
				(thermal_gap 0.5)
				(thermal_bridge_width 0.5)
				(island_removal_mode 0)
			)
			(polygon
				(pts
					(xy 405.9936 -34.567368) (xy 405.9936 -34.059368) (xy 405.6126 -34.059368) (xy 405.6126 -34.567368)
				)
			)
		)
	)
	(footprint ""
		(layer "B.Cu")
		(at 99.034854 -73.51014)
		(property "Reference" "C8P26"
			(at 0 0 0)
			(layer "B.SilkS")
			(hide yes)
			(effects
				(font
					(size 1.27 1.27)
				)
				(justify mirror)
			)
		)
		(property "Value" ""
			(at 0 0 0)
			(layer "B.Fab")
			(effects
				(font
					(size 1.27 1.27)
				)
				(justify mirror)
			)
		)
		(duplicate_pad_numbers_are_jumpers no)
		(fp_poly
			(pts
				(xy 0.7239 -0.2159) (xy -0.7239 -0.2159) (xy -0.7239 1.9939) (xy 0.7239 1.9939)
			)
			(stroke
				(width 0)
				(type default)
			)
			(fill no)
			(layer "B.CrtYd")
		)
		(fp_line
			(start -0.7239 -0.2159)
			(end 0.7239 -0.2159)
			(stroke
				(width 0.1)
				(type default)
			)
			(layer "B.Fab")
		)
		(fp_line
			(start -0.7239 1.9939)
			(end -0.7239 -0.2159)
			(stroke
				(width 0.1)
				(type default)
			)
			(layer "B.Fab")
		)
		(fp_line
			(start 0.7239 -0.2159)
			(end 0.7239 1.9939)
			(stroke
				(width 0.1)
				(type default)
			)
			(layer "B.Fab")
		)
		(fp_line
			(start 0.7239 1.9939)
			(end -0.7239 1.9939)
			(stroke
				(width 0.1)
				(type default)
			)
			(layer "B.Fab")
		)
		(pad "1" smd rect
			(at 0 0 180)
			(size 1.27 1.016)
			(layers "B.Cu" "B.Mask" "B.Paste")
			(net "PVCCIN_CPU1")
		)
		(pad "2" smd rect
			(at 0 1.778 180)
			(size 1.27 1.016)
			(layers "B.Cu" "B.Mask" "B.Paste")
			(net "GND")
		)
		(zone
			(layer "B.Cu")
			(hatch none 0.5)
			(connect_pads
				(clearance 0)
			)
			(min_thickness 0.25)
			(keepout
				(tracks not_allowed)
				(vias allowed)
				(pads allowed)
				(copperpour not_allowed)
				(footprints allowed)
			)
			(placement
				(enabled no)
				(sheetname "")
			)
			(fill
				(thermal_gap 0.5)
				(thermal_bridge_width 0.5)
				(island_removal_mode 0)
			)
			(polygon
				(pts
					(xy 99.669854 -73.00214) (xy 98.399854 -73.00214) (xy 98.399854 -72.24014) (xy 99.669854 -72.24014)
				)
			)
		)
	)
	(footprint ""
		(layer "B.Cu")
		(at 379.984 -87.3125 180)
		(property "Reference" "R7D3"
			(at 0 0 0)
			(layer "B.SilkS")
			(hide yes)
			(effects
				(font
					(size 1.27 1.27)
				)
				(justify mirror)
			)
		)
		(property "Value" ""
			(at 0 0 0)
			(layer "B.Fab")
			(effects
				(font
					(size 1.27 1.27)
				)
				(justify mirror)
			)
		)
		(duplicate_pad_numbers_are_jumpers no)
		(fp_poly
			(pts
				(xy 0.2794 -0.1016) (xy -0.2794 -0.1016) (xy -0.2794 0.9906) (xy 0.2794 0.9906)
			)
			(stroke
				(width 0)
				(type default)
			)
			(fill no)
			(layer "B.CrtYd")
		)
		(fp_line
			(start 0.2794 0.9906)
			(end -0.2794 0.9906)
			(stroke
				(width 0.1)
				(type default)
			)
			(layer "B.Fab")
		)
		(fp_line
			(start 0.2794 -0.1016)
			(end 0.2794 0.9906)
			(stroke
				(width 0.1)
				(type default)
			)
			(layer "B.Fab")
		)
		(fp_line
			(start -0.2794 0.9906)
			(end -0.2794 -0.1016)
			(stroke
				(width 0.1)
				(type default)
			)
			(layer "B.Fab")
		)
		(fp_line
			(start -0.2794 -0.1016)
			(end 0.2794 -0.1016)
			(stroke
				(width 0.1)
				(type default)
			)
			(layer "B.Fab")
		)
		(pad "1" smd rect
			(at 0 0)
			(size 0.508 0.508)
			(layers "B.Cu" "B.Mask" "B.Paste")
			(net "P3V3_STBY")
		)
		(pad "2" smd rect
			(at 0 0.889)
			(size 0.508 0.508)
			(layers "B.Cu" "B.Mask" "B.Paste")
			(net "IRQ_LPC_SERIRQ_N")
		)
		(zone
			(layer "B.Cu")
			(hatch none 0.5)
			(connect_pads
				(clearance 0)
			)
			(min_thickness 0.25)
			(keepout
				(tracks not_allowed)
				(vias allowed)
				(pads allowed)
				(copperpour not_allowed)
				(footprints allowed)
			)
			(placement
				(enabled no)
				(sheetname "")
			)
			(fill
				(thermal_gap 0.5)
				(thermal_bridge_width 0.5)
				(island_removal_mode 0)
			)
			(polygon
				(pts
					(xy 379.73 -87.9475) (xy 380.238 -87.9475) (xy 380.238 -87.5665) (xy 379.73 -87.5665)
				)
			)
		)
		(zone
			(layer "B.Cu")
			(hatch none 0.5)
			(connect_pads
				(clearance 0)
			)
			(min_thickness 0.25)
			(keepout
				(tracks allowed)
				(vias not_allowed)
				(pads allowed)
				(copperpour not_allowed)
				(footprints allowed)
			)
			(placement
				(enabled no)
				(sheetname "")
			)
			(fill
				(thermal_gap 0.5)
				(thermal_bridge_width 0.5)
				(island_removal_mode 0)
			)
			(polygon
				(pts
					(xy 379.73 -87.5665) (xy 380.238 -87.5665) (xy 380.238 -87.9475) (xy 379.73 -87.9475)
				)
			)
		)
	)
	(footprint ""
		(layer "B.Cu")
		(at 245.7323 -140.208 -90)
		(property "Reference" "C5G64"
			(at -1.14681 0.76708 0)
			(unlocked yes)
			(layer "B.SilkS")
			(effects
				(font
					(size 0.7874 0.5842)
					(thickness 0.1524)
				)
				(justify mirror)
			)
		)
		(property "Value" ""
			(at 0 0 90)
			(layer "B.Fab")
			(effects
				(font
					(size 1.27 1.27)
				)
				(justify mirror)
			)
		)
		(duplicate_pad_numbers_are_jumpers no)
		(fp_rect
			(start 0.4953 1.6002)
			(end -0.4953 -0.2032)
			(stroke
				(width 0)
				(type default)
			)
			(fill no)
			(layer "B.CrtYd")
		)
		(fp_line
			(start -0.4953 1.6002)
			(end 0.4953 1.6002)
			(stroke
				(width 0.1)
				(type default)
			)
			(layer "B.Fab")
		)
		(fp_line
			(start 0.4953 1.6002)
			(end 0.4953 -0.2032)
			(stroke
				(width 0.1)
				(type default)
			)
			(layer "B.Fab")
		)
		(fp_line
			(start -0.4953 -0.2032)
			(end -0.4953 1.6002)
			(stroke
				(width 0.1)
				(type default)
			)
			(layer "B.Fab")
		)
		(fp_line
			(start 0.4953 -0.2032)
			(end -0.4953 -0.2032)
			(stroke
				(width 0.1)
				(type default)
			)
			(layer "B.Fab")
		)
		(pad "1" smd rect
			(at 0 0 90)
			(size 0.762 0.889)
			(layers "B.Cu" "B.Mask" "B.Paste")
			(net "PVDDQ_DEF")
		)
		(pad "2" smd rect
			(at 0 1.397 90)
			(size 0.762 0.889)
			(layers "B.Cu" "B.Mask" "B.Paste")
			(net "GND")
		)
		(zone
			(layer "B.Cu")
			(hatch none 0.5)
			(connect_pads
				(clearance 0)
			)
			(min_thickness 0.25)
			(keepout
				(tracks not_allowed)
				(vias allowed)
				(pads allowed)
				(copperpour not_allowed)
				(footprints allowed)
			)
			(placement
				(enabled no)
				(sheetname "")
			)
			(fill
				(thermal_gap 0.5)
				(thermal_bridge_width 0.5)
				(island_removal_mode 0)
			)
			(polygon
				(pts
					(xy 244.7798 -139.827) (xy 245.2878 -139.827) (xy 245.2878 -140.589) (xy 244.7798 -140.589)
				)
			)
		)
	)
	(footprint ""
		(layer "B.Cu")
		(at 496.919504 -35.458146 180)
		(property "Reference" "U9F2"
			(at 0.4064 2.41427 180)
			(unlocked yes)
			(layer "B.SilkS")
			(effects
				(font
					(size 0.7874 0.5842)
					(thickness 0.1524)
				)
				(justify mirror)
			)
		)
		(property "Value" ""
			(at 0 0 0)
			(layer "B.Fab")
			(effects
				(font
					(size 1.27 1.27)
				)
				(justify mirror)
			)
		)
		(duplicate_pad_numbers_are_jumpers no)
		(fp_line
			(start -1.269238 1.8034)
			(end -1.77673 1.8034)
			(stroke
				(width 0.1524)
				(type default)
			)
			(layer "B.SilkS")
		)
		(fp_line
			(start -1.269238 -0.3048)
			(end -1.77673 -0.3048)
			(stroke
				(width 0.1524)
				(type default)
			)
			(layer "B.SilkS")
		)
		(fp_circle
			(center 0.967994 -0.635)
			(end 0.840994 -0.635)
			(stroke
				(width 0.254)
				(type default)
			)
			(fill no)
			(layer "B.SilkS")
		)
		(fp_rect
			(start -0.3302 1.8034)
			(end -2.7432 -0.3048)
			(stroke
				(width 0)
				(type default)
			)
			(fill no)
			(layer "B.CrtYd")
		)
		(fp_line
			(start -0.3302 1.8034)
			(end -0.3302 -0.3048)
			(stroke
				(width 0.1)
				(type default)
			)
			(layer "B.Fab")
		)
		(fp_line
			(start -0.3302 -0.3048)
			(end -2.7432 -0.3048)
			(stroke
				(width 0.1)
				(type default)
			)
			(layer "B.Fab")
		)
		(fp_line
			(start -2.7432 1.8034)
			(end -0.3302 1.8034)
			(stroke
				(width 0.1)
				(type default)
			)
			(layer "B.Fab")
		)
		(fp_line
			(start -2.7432 -0.3048)
			(end -2.7432 1.8034)
			(stroke
				(width 0.1)
				(type default)
			)
			(layer "B.Fab")
		)
		(fp_circle
			(center 0.967994 -0.635)
			(end 0.840994 -0.635)
			(stroke
				(width 0.254)
				(type default)
			)
			(fill no)
			(layer "B.Fab")
		)
		(pad "1" smd rect
			(at 0 0)
			(size 1.524 0.254)
			(layers "B.Cu" "B.Mask" "B.Paste")
			(net "SP2_BMC_CM_UART_TX_R")
		)
		(pad "2" smd rect
			(at 0 0.499872)
			(size 1.524 0.254)
			(layers "B.Cu" "B.Mask" "B.Paste")
			(net "UART_BMC_TXD5")
		)
		(pad "3" smd rect
			(at 0 0.999744)
			(size 1.524 0.254)
			(layers "B.Cu" "B.Mask" "B.Paste")
			(net "SP1_BMC_HOST_UART_TX")
		)
		(pad "4" smd rect
			(at 0 1.499616)
			(size 1.524 0.254)
			(layers "B.Cu" "B.Mask" "B.Paste")
			(net "GND")
		)
		(pad "5" smd rect
			(at -3.048 1.499616)
			(size 1.524 0.254)
			(layers "B.Cu" "B.Mask" "B.Paste")
			(net "FM_UARTSW_MSB_N")
		)
		(pad "6" smd rect
			(at -3.048 0.999744)
			(size 1.524 0.254)
			(layers "B.Cu" "B.Mask" "B.Paste")
			(net "FM_UARTSW_LSB_N")
		)
		(pad "7" smd rect
			(at -3.048 0.499872)
			(size 1.524 0.254)
			(layers "B.Cu" "B.Mask" "B.Paste")
			(net "UART_MUX_OUT_R")
		)
		(pad "8" smd rect
			(at -3.048 0)
			(size 1.524 0.254)
			(layers "B.Cu" "B.Mask" "B.Paste")
			(net "P3V3_STBY")
		)
	)
	(footprint ""
		(layer "B.Cu")
		(at 162.687 -83.058 90)
		(property "Reference" "R7P3"
			(at 0 0 90)
			(layer "B.SilkS")
			(hide yes)
			(effects
				(font
					(size 1.27 1.27)
				)
				(justify mirror)
			)
		)
		(property "Value" ""
			(at 0 0 90)
			(layer "B.Fab")
			(effects
				(font
					(size 1.27 1.27)
				)
				(justify mirror)
			)
		)
		(duplicate_pad_numbers_are_jumpers no)
		(fp_poly
			(pts
				(xy 0.2794 -0.1016) (xy -0.2794 -0.1016) (xy -0.2794 0.9906) (xy 0.2794 0.9906)
			)
			(stroke
				(width 0)
				(type default)
			)
			(fill no)
			(layer "B.CrtYd")
		)
		(fp_line
			(start 0.2794 -0.1016)
			(end 0.2794 0.9906)
			(stroke
				(width 0.1)
				(type default)
			)
			(layer "B.Fab")
		)
		(fp_line
			(start -0.2794 -0.1016)
			(end 0.2794 -0.1016)
			(stroke
				(width 0.1)
				(type default)
			)
			(layer "B.Fab")
		)
		(fp_line
			(start 0.2794 0.9906)
			(end -0.2794 0.9906)
			(stroke
				(width 0.1)
				(type default)
			)
			(layer "B.Fab")
		)
		(fp_line
			(start -0.2794 0.9906)
			(end -0.2794 -0.1016)
			(stroke
				(width 0.1)
				(type default)
			)
			(layer "B.Fab")
		)
		(pad "1" smd rect
			(at 0 0 270)
			(size 0.508 0.508)
			(layers "B.Cu" "B.Mask" "B.Paste")
			(net "CLK_100M_CPU1_PE_REFCLK_DP")
		)
		(pad "2" smd rect
			(at 0 0.889 270)
			(size 0.508 0.508)
			(layers "B.Cu" "B.Mask" "B.Paste")
			(net "GND")
		)
		(zone
			(layer "B.Cu")
			(hatch none 0.5)
			(connect_pads
				(clearance 0)
			)
			(min_thickness 0.25)
			(keepout
				(tracks allowed)
				(vias not_allowed)
				(pads allowed)
				(copperpour not_allowed)
				(footprints allowed)
			)
			(placement
				(enabled no)
				(sheetname "")
			)
			(fill
				(thermal_gap 0.5)
				(thermal_bridge_width 0.5)
				(island_removal_mode 0)
			)
			(polygon
				(pts
					(xy 162.941 -83.312) (xy 162.941 -82.804) (xy 163.322 -82.804) (xy 163.322 -83.312)
				)
			)
		)
		(zone
			(layer "B.Cu")
			(hatch none 0.5)
			(connect_pads
				(clearance 0)
			)
			(min_thickness 0.25)
			(keepout
				(tracks not_allowed)
				(vias allowed)
				(pads allowed)
				(copperpour not_allowed)
				(footprints allowed)
			)
			(placement
				(enabled no)
				(sheetname "")
			)
			(fill
				(thermal_gap 0.5)
				(thermal_bridge_width 0.5)
				(island_removal_mode 0)
			)
			(polygon
				(pts
					(xy 163.322 -83.312) (xy 163.322 -82.804) (xy 162.941 -82.804) (xy 162.941 -83.312)
				)
			)
		)
	)
)
